# S9S_MB_2U (Grand Teton) — schematic netlist excerpt (pin names and nets, part order shuffled) for the footprints in the layout excerpt that follows; sources: Cadence DE-HDL packaged netlist, KiCad conversion of 03242023_DA0F0TMBIJ0_F0T_Motherboard_J_brd_V01_OCP.brd

J21  SCONN288_ADR50017P130CC  SCONN288_ADR50017-P130CC IO  pkg DDR288S_1-1VXB  page 102
  VIN_BULK0  = P12V_S3_AUX_CPU1_NVDIMM
  RFU0  = TP_CHC_CPU1_DIMM1_FRU_0
  VIN_MGMT  = P3V3_AUX
  HSCL  = I3C_SPD_DDRABCD_CPU1_LVC1_SCL_4
  HSDA  = I3C_SPD_DDRABCD_CPU1_LVC1_SDA
  VSS0  = GND
  DQ0_A  = M_C_CPU1_SA_DQ<0>
  VSS1  = GND
  DQ1_A  = M_C_CPU1_SA_DQ<1>
  VSS2  = GND
  DQS0_A_T  = M_C_CPU1_SA_DQS_DP<0>
  DQS0_A_C  = M_C_CPU1_SA_DQS_DN<0>
  VSS3  = GND
  DQ4_A  = M_C_CPU1_SA_DQ<4>
  VSS4  = GND
  DQ5_A  = M_C_CPU1_SA_DQ<5>
  VSS5  = GND
  DQ8_A  = M_C_CPU1_SA_DQ<8>
  VSS6  = GND
  DQ9_A  = M_C_CPU1_SA_DQ<9>
  VSS7  = GND
  DQS1_A_T  = M_C_CPU1_SA_DQS_DP<1>
  DQS1_A_C  = M_C_CPU1_SA_DQS_DN<1>
  VSS8  = GND
  DQ12_A  = M_C_CPU1_SA_DQ<12>
  VSS9  = GND
  DQ13_A  = M_C_CPU1_SA_DQ<13>
  VSS10  = GND
  DQ16_A  = M_C_CPU1_SA_DQ<16>
  VSS11  = GND
  DQ17_A  = M_C_CPU1_SA_DQ<17>
  VSS12  = GND
  DQS2_A_T  = M_C_CPU1_SA_DQS_DP<2>
  DQS2_A_C  = M_C_CPU1_SA_DQS_DN<2>
  VSS13  = GND
  DQ20_A  = M_C_CPU1_SA_DQ<20>
  VSS14  = GND
  DQ21_A  = M_C_CPU1_SA_DQ<21>
  VSS15  = GND
  DQ24_A  = M_C_CPU1_SA_DQ<24>
  VSS16  = GND
  DQ25_A  = M_C_CPU1_SA_DQ<25>
  VSS17  = GND
  DQS3_A_T  = M_C_CPU1_SA_DQS_DP<3>
  DQS3_A_C  = M_C_CPU1_SA_DQS_DN<3>
  VSS18  = GND
  DQ28_A  = M_C_CPU1_SA_DQ<28>
  VSS19  = GND
  DQ29_A  = M_C_CPU1_SA_DQ<29>
  VSS20  = GND
  CB0_A  = M_C_CPU1_SA_CB<0>
  VSS21  = GND
  CB1_A  = M_C_CPU1_SA_CB<1>
  VSS22  = GND
  DQS4_A_T  = M_C_CPU1_SA_DQS_DP<4>
  DQS4_A_C  = M_C_CPU1_SA_DQS_DN<4>
  VSS23  = GND
  CB4_A  = M_C_CPU1_SA_CB<4>
  VSS24  = GND
  CB5_A  = M_C_CPU1_SA_CB<5>
  VSS25  = GND
  ALERT_N  = M_C_CPU1_ALERT_N
  VSS26  = GND
  CS0_A_N  = M_C_CPU1_SA_CS_N<0>
  VSS27  = GND
  CA0_A  = M_C_CPU1_SA_CA<0>
  VSS28  = GND
  CA2_A  = M_C_CPU1_SA_CA<2>
  VSS29  = GND
  CA4_A  = M_C_CPU1_SA_CA<4>
  VSS30  = GND
  CA6_A  = M_C_CPU1_SA_CA<6>
  VSS31  = GND
  PAR_A  = M_C_CPU1_SA_PAR
  VSS32  = GND
  CA0_B  = M_C_CPU1_SB_CA<0>
  VSS33  = GND
  CA2_B  = M_C_CPU1_SB_CA<2>
  VSS34  = GND
  CA4_B  = M_C_CPU1_SB_CA<4>
  VSS35  = GND
  CA6_B  = M_C_CPU1_SB_CA<6>
  VSS36  = GND
  CS0_B_N  = M_C_CPU1_SB_CS_N<0>
  VSS37  = GND
  \lbd||rsp_a_n\  = M_C_CPU1_SA_RSP<0>
  \lbs||rsp_b_n\  = M_C_CPU1_SB_RSP<0>
  VSS38  = GND
  CB4_B  = M_C_CPU1_SB_CB<4>
  VSS39  = GND
  CB5_B  = M_C_CPU1_SB_CB<5>
  VSS40  = GND
  \dqs9_b_t||tdqs9_b_t||dbi4_b_n\  = M_C_CPU1_SB_DQS_DP<9>
  \dqs9_b_c||tdqs9_b_c\  = M_C_CPU1_SB_DQS_DN<9>
  VSS41  = GND
  CB0_B  = M_C_CPU1_SB_CB<0>
  VSS42  = GND
  CB1_B  = M_C_CPU1_SB_CB<1>
  VSS43  = GND
  DQ0_B  = M_C_CPU1_SB_DQ<0>
  VSS44  = GND
  DQ1_B  = M_C_CPU1_SB_DQ<1>
  VSS45  = GND
  DQS0_B_T  = M_C_CPU1_SB_DQS_DP<0>
  DQS0_B_C  = M_C_CPU1_SB_DQS_DN<0>
  VSS46  = GND
  DQ4_B  = M_C_CPU1_SB_DQ<4>
  VSS47  = GND
  DQ5_B  = M_C_CPU1_SB_DQ<5>
  VSS48  = GND
  DQ8_B  = M_C_CPU1_SB_DQ<8>
  VSS49  = GND
  DQ9_B  = M_C_CPU1_SB_DQ<9>
  VSS50  = GND
  DQS1_B_T  = M_C_CPU1_SB_DQS_DP<1>
  DQS1_B_C  = M_C_CPU1_SB_DQS_DN<1>
  VSS51  = GND
  DQ12_B  = M_C_CPU1_SB_DQ<12>
  VSS52  = GND
  DQ13_B  = M_C_CPU1_SB_DQ<13>
  VSS53  = GND
  DQ16_B  = M_C_CPU1_SB_DQ<16>
  VSS54  = GND
  DQ17_B  = M_C_CPU1_SB_DQ<17>
  VSS55  = GND
  DQS2_B_T  = M_C_CPU1_SB_DQS_DP<2>
  DQS2_B_C  = M_C_CPU1_SB_DQS_DN<2>
  VSS56  = GND
  DQ20_B  = M_C_CPU1_SB_DQ<20>
  VSS57  = GND
  DQ21_B  = M_C_CPU1_SB_DQ<21>
  VSS58  = GND
  DQ24_B  = M_C_CPU1_SB_DQ<24>
  VSS59  = GND
  DQ25_B  = M_C_CPU1_SB_DQ<25>
  VSS60  = GND
  DQS3_B_T  = M_C_CPU1_SB_DQS_DP<3>
  DQS3_B_C  = M_C_CPU1_SB_DQS_DN<3>
  VSS61  = GND
  DQ28_B  = M_C_CPU1_SB_DQ<28>
  VSS62  = GND
  DQ29_B  = M_C_CPU1_SB_DQ<29>
  VSS63  = GND
  RFU1  = TP_CHC_CPU1_DIMM1_FRU_1
  VIN_BULK1  = P12V_S3_AUX_CPU1_NVDIMM
  VIN_BULK2  = P12V_S3_AUX_CPU1_NVDIMM
  \pwr_good||fail_n\  = PWRGD_CHC_CPU1_DIMM1
  HSA  = PD_CHC_CPU1_DIMM1_SAA
  RFU2  = TP_CHC_CPU1_DIMM1_FRU_2
  RFU3  = TP_CHC_CPU1_DIMM1_FRU_3
  VSS64  = GND
  DQ2_A  = M_C_CPU1_SA_DQ<2>
  VSS65  = GND
  DQ3_A  = M_C_CPU1_SA_DQ<3>
  VSS66  = GND
  \dqs5_a_c||tdqs5_a_c||dqs5_a_t||tdqs5_a_t\  = M_C_CPU1_SA_DQS_DN<5>
  \dqs5_a_t||tdqs5_a_t\  = M_C_CPU1_SA_DQS_DP<5>
  VSS67  = GND
  DQ6_A  = M_C_CPU1_SA_DQ<6>
  VSS68  = GND
  DQ7_A  = M_C_CPU1_SA_DQ<7>
  VSS69  = GND
  DQ10_A  = M_C_CPU1_SA_DQ<10>
  VSS70  = GND
  DQ11_A  = M_C_CPU1_SA_DQ<11>
  VSS71  = GND
  \dqs6_a_c||tdqs6_a_c||dqs6_a_t||tdqs6_a_t\  = M_C_CPU1_SA_DQS_DN<6>
  \dqs6_a_t||tdqs6_a_t\  = M_C_CPU1_SA_DQS_DP<6>
  VSS72  = GND
  DQ14_A  = M_C_CPU1_SA_DQ<14>
  VSS73  = GND
  DQ15_A  = M_C_CPU1_SA_DQ<15>
  VSS74  = GND
  DQ18_A  = M_C_CPU1_SA_DQ<18>
  VSS75  = GND
  DQ19_A  = M_C_CPU1_SA_DQ<19>
  VSS76  = GND
  \dqs7_a_c||tdqs7_a_c\  = M_C_CPU1_SA_DQS_DN<7>
  \dqs7_a_t||tdqs7_a_t\  = M_C_CPU1_SA_DQS_DP<7>
  VSS77  = GND
  DQ22_A  = M_C_CPU1_SA_DQ<22>
  VSS78  = GND
  DQ23_A  = M_C_CPU1_SA_DQ<23>
  VSS79  = GND
  DQ26_A  = M_C_CPU1_SA_DQ<26>
  VSS80  = GND
  DQ27_A  = M_C_CPU1_SA_DQ<27>
  VSS81  = GND
  \dqs8_a_c||tdqs8_a_c\  = M_C_CPU1_SA_DQS_DN<8>
  \dqs8_a_t||tdqs8_a_t\  = M_C_CPU1_SA_DQS_DP<8>
  VSS82  = GND
  DQ30_A  = M_C_CPU1_SA_DQ<30>
  VSS83  = GND
  DQ31_A  = M_C_CPU1_SA_DQ<31>
  VSS84  = GND
  CB2_A  = M_C_CPU1_SA_CB<2>
  VSS85  = GND
  CB3_A  = M_C_CPU1_SA_CB<3>
  VSS86  = GND
  \dqs9_a_c||tdqs9_a_c\  = M_C_CPU1_SA_DQS_DN<9>
  \dqs9_a_t||tdqs9_a_t\  = M_C_CPU1_SA_DQS_DP<9>
  VSS87  = GND
  CB6_A  = M_C_CPU1_SA_CB<6>
  VSS88  = GND
  CB7_A  = M_C_CPU1_SA_CB<7>
  VSS89  = GND
  RESET_N  = RST_M_CD_CPU1_FPGA_N
  VSS90  = GND
  CS1_A_N  = M_C_CPU1_SA_CS_N<1>
  VSS91  = GND
  CA1_A  = M_C_CPU1_SA_CA<1>
  VSS92  = GND
  CA3_A  = M_C_CPU1_SA_CA<3>
  VSS93  = GND
  CA5_A  = M_C_CPU1_SA_CA<5>
  VSS94  = GND
  CK_T  = M_C_CPU1_CLK_DP<0>
  CK_C  = M_C_CPU1_CLK_DN<0>
  VSS95  = GND
  RFU4  = TP_CHC_CPU1_DIMM1_FRU_4
  CA1_B  = M_C_CPU1_SB_CA<1>
  VSS96  = GND
  CA3_B  = M_C_CPU1_SB_CA<3>
  VSS97  = GND
  CA5_B  = M_C_CPU1_SB_CA<5>
  VSS98  = GND
  PAR_B  = M_C_CPU1_SB_PAR
  VSS99  = GND
  CS1_B_N  = M_C_CPU1_SB_CS_N<1>
  VSS100  = GND
  RFU5  = TP_CHC_CPU1_DIMM1_FRU_5
  RFU6  = TP_CHC_CPU1_DIMM1_FRU_6
  VSS101  = GND
  CB6_B  = M_C_CPU1_SB_CB<6>
  VSS102  = GND
  CB7_B  = M_C_CPU1_SB_CB<7>
  VSS103  = GND
  DQS4_B_C  = M_C_CPU1_SB_DQS_DN<4>
  DQS4_B_T  = M_C_CPU1_SB_DQS_DP<4>
  VSS104  = GND
  CB2_B  = M_C_CPU1_SB_CB<2>
  VSS105  = GND
  CB3_B  = M_C_CPU1_SB_CB<3>
  VSS106  = GND
  DQ2_B  = M_C_CPU1_SB_DQ<2>
  VSS107  = GND
  DQ3_B  = M_C_CPU1_SB_DQ<3>
  VSS108  = GND
  \dqs5_b_c||tdqs5_b_c\  = M_C_CPU1_SB_DQS_DN<5>
  \dqs5_b_t||tdqs5_b_t\  = M_C_CPU1_SB_DQS_DP<5>
  VSS109  = GND
  DQ6_B  = M_C_CPU1_SB_DQ<6>
  VSS110  = GND
  DQ7_B  = M_C_CPU1_SB_DQ<7>
  VSS111  = GND
  DQ10_B  = M_C_CPU1_SB_DQ<10>
  VSS112  = GND
  DQ11_B  = M_C_CPU1_SB_DQ<11>
  VSS113  = GND
  \dqs6_b_c||tdqs6_b_c\  = M_C_CPU1_SB_DQS_DN<6>
  \dqs6_b_t||tdqs6_b_t\  = M_C_CPU1_SB_DQS_DP<6>
  VSS114  = GND
  DQ14_B  = M_C_CPU1_SB_DQ<14>
  VSS115  = GND
  DQ15_B  = M_C_CPU1_SB_DQ<15>
  VSS116  = GND
  DQ18_B  = M_C_CPU1_SB_DQ<18>
  VSS117  = GND
  DQ19_B  = M_C_CPU1_SB_DQ<19>
  VSS118  = GND
  \dqs7_b_c||tdqs7_b_c\  = M_C_CPU1_SB_DQS_DN<7>
  \dqs7_b_t||tdqs7_b_t\  = M_C_CPU1_SB_DQS_DP<7>
  VSS119  = GND
  DQ22_B  = M_C_CPU1_SB_DQ<22>
  VSS120  = GND
  DQ23_B  = M_C_CPU1_SB_DQ<23>
  VSS121  = GND
  DQ26_B  = M_C_CPU1_SB_DQ<26>
  VSS122  = GND
  DQ27_B  = M_C_CPU1_SB_DQ<27>
  VSS123  = GND
  \dqs8_b_c||tdqs8_b_c\  = M_C_CPU1_SB_DQS_DN<8>
  \dqs8_b_t||tdqs8_b_t\  = M_C_CPU1_SB_DQS_DP<8>
  VSS124  = GND
  DQ30_B  = M_C_CPU1_SB_DQ<30>
  VSS125  = GND
  DQ31_B  = M_C_CPU1_SB_DQ<31>
  VSS126  = GND
  G1  = GND
  G2  = GND
  G3  = GND

(kicad_pcb
	(version 20260206)
	(generator "pcbnew")
	(generator_version "10.0")
	(general
		(thickness 1.6)
		(legacy_teardrops no)
	)
	(paper "A4")
	(title_block
		(title "03242023_DA0F0TMBIJ0_F0T_Motherboard_J_brd_V01_OCP.brd")
		(comment 1 "Grand Teton / footprint 663 of 6105 (J21), pads 1-45 of 291")
	)
	(layers
		(0 "F.Cu" signal "TOP")
		(4 "In1.Cu" signal "GND")
		(6 "In2.Cu" signal "IN1")
		(8 "In3.Cu" signal "GND1")
		(10 "In4.Cu" signal "IN2")
		(12 "In5.Cu" signal "GND2")
		(14 "In6.Cu" signal "IN3")
		(16 "In7.Cu" signal "GND3")
		(18 "In8.Cu" signal "VCC")
		(20 "In9.Cu" signal "VCC1")
		(22 "In10.Cu" signal "GND4")
		(24 "In11.Cu" signal "IN4")
		(26 "In12.Cu" signal "GND5")
		(28 "In13.Cu" signal "IN5")
		(30 "In14.Cu" signal "GND6")
		(32 "In15.Cu" signal "IN6")
		(34 "In16.Cu" signal "GND7")
		(2 "B.Cu" signal "BOTTOM")
		(9 "F.Adhes" user "F.Adhesive")
		(11 "B.Adhes" user "B.Adhesive")
		(13 "F.Paste" user "Package Geometry/Pastemask Top")
		(15 "B.Paste" user "Package Geometry/Pastemask Bottom")
		(5 "F.SilkS" user "Ref Des/Silkscreen Top")
		(7 "B.SilkS" user "Ref Des/Silkscreen Bottom")
		(1 "F.Mask" user "Board Geometry/Soldermask Top")
		(3 "B.Mask" user "Board Geometry/Soldermask Bottom")
		(17 "Dwgs.User" user "User.Drawings")
		(19 "Cmts.User" user "User.Comments")
		(21 "Eco1.User" user "User.Eco1")
		(23 "Eco2.User" user "User.Eco2")
		(25 "Edge.Cuts" user "Board Geometry/Outline")
		(27 "Margin" user)
		(31 "F.CrtYd" user "Package Geometry/Place Bound Top")
		(29 "B.CrtYd" user "Package Geometry/Place Bound Bottom")
		(35 "F.Fab" user "Ref Des/Assembly Top")
		(33 "B.Fab" user "Ref Des/Assembly Bottom")
	)
	(footprint ""
		(layer "F.Cu")
		(at 25.27808 -258.091686)
		(property "Reference" "J21"
			(at -0.325882 -81.821274 0)
			(unlocked yes)
			(layer "F.SilkS")
			(effects
				(font
					(size 0.7874 0.5842)
					(thickness 0.1524)
				)
				(justify left)
			)
		)
		(property "Value" ""
			(at 0 0 0)
			(layer "F.Fab")
			(effects
				(font
					(size 1.27 1.27)
				)
			)
		)
		(duplicate_pad_numbers_are_jumpers no)
		(pad "1" smd rect
			(at -2.050034 -63.324994 270)
			(size 0.519938 1.4986)
			(layers "F.Cu" "F.Mask" "F.Paste")
			(net "P12V_S3_AUX_CPU1_NVDIMM")
		)
		(pad "2" smd rect
			(at -2.050034 -62.47511 270)
			(size 0.519938 1.4986)
			(layers "F.Cu" "F.Mask" "F.Paste")
			(net "TP_CHC_CPU1_DIMM1_FRU_0")
		)
		(pad "3" smd rect
			(at -2.050034 -61.624972 270)
			(size 0.519938 1.4986)
			(layers "F.Cu" "F.Mask" "F.Paste")
			(net "P3V3_AUX")
		)
		(pad "4" smd rect
			(at -2.050034 -60.775088 270)
			(size 0.519938 1.4986)
			(layers "F.Cu" "F.Mask" "F.Paste")
			(net "I3C_SPD_DDRABCD_CPU1_LVC1_SCL_4")
		)
		(pad "5" smd rect
			(at -2.050034 -59.92495 270)
			(size 0.519938 1.4986)
			(layers "F.Cu" "F.Mask" "F.Paste")
			(net "I3C_SPD_DDRABCD_CPU1_LVC1_SDA")
		)
		(pad "6" smd rect
			(at -2.050034 -59.075066 270)
			(size 0.519938 1.4986)
			(layers "F.Cu" "F.Mask" "F.Paste")
			(net "GND")
		)
		(pad "7" smd rect
			(at -2.050034 -58.224928 270)
			(size 0.519938 1.4986)
			(layers "F.Cu" "F.Mask" "F.Paste")
			(net "M_C_CPU1_SA_DQ<0>")
		)
		(pad "8" smd rect
			(at -2.050034 -57.375044 270)
			(size 0.519938 1.4986)
			(layers "F.Cu" "F.Mask" "F.Paste")
			(net "GND")
		)
		(pad "9" smd rect
			(at -2.050034 -56.524906 270)
			(size 0.519938 1.4986)
			(layers "F.Cu" "F.Mask" "F.Paste")
			(net "M_C_CPU1_SA_DQ<1>")
		)
		(pad "10" smd rect
			(at -2.050034 -55.675022 270)
			(size 0.519938 1.4986)
			(layers "F.Cu" "F.Mask" "F.Paste")
			(net "GND")
		)
		(pad "11" smd rect
			(at -2.050034 -54.824884 270)
			(size 0.519938 1.4986)
			(layers "F.Cu" "F.Mask" "F.Paste")
			(net "M_C_CPU1_SA_DQS_DP<0>")
		)
		(pad "12" smd rect
			(at -2.050034 -53.975 270)
			(size 0.519938 1.4986)
			(layers "F.Cu" "F.Mask" "F.Paste")
			(net "M_C_CPU1_SA_DQS_DN<0>")
		)
		(pad "13" smd rect
			(at -2.050034 -53.125116 270)
			(size 0.519938 1.4986)
			(layers "F.Cu" "F.Mask" "F.Paste")
			(net "GND")
		)
		(pad "14" smd rect
			(at -2.050034 -52.274978 270)
			(size 0.519938 1.4986)
			(layers "F.Cu" "F.Mask" "F.Paste")
			(net "M_C_CPU1_SA_DQ<4>")
		)
		(pad "15" smd rect
			(at -2.050034 -51.425094 270)
			(size 0.519938 1.4986)
			(layers "F.Cu" "F.Mask" "F.Paste")
			(net "GND")
		)
		(pad "16" smd rect
			(at -2.050034 -50.574956 270)
			(size 0.519938 1.4986)
			(layers "F.Cu" "F.Mask" "F.Paste")
			(net "M_C_CPU1_SA_DQ<5>")
		)
		(pad "17" smd rect
			(at -2.050034 -49.725072 270)
			(size 0.519938 1.4986)
			(layers "F.Cu" "F.Mask" "F.Paste")
			(net "GND")
		)
		(pad "18" smd rect
			(at -2.050034 -48.874934 270)
			(size 0.519938 1.4986)
			(layers "F.Cu" "F.Mask" "F.Paste")
			(net "M_C_CPU1_SA_DQ<8>")
		)
		(pad "19" smd rect
			(at -2.050034 -48.02505 270)
			(size 0.519938 1.4986)
			(layers "F.Cu" "F.Mask" "F.Paste")
			(net "GND")
		)
		(pad "20" smd rect
			(at -2.050034 -47.174912 270)
			(size 0.519938 1.4986)
			(layers "F.Cu" "F.Mask" "F.Paste")
			(net "M_C_CPU1_SA_DQ<9>")
		)
		(pad "21" smd rect
			(at -2.050034 -46.325028 270)
			(size 0.519938 1.4986)
			(layers "F.Cu" "F.Mask" "F.Paste")
			(net "GND")
		)
		(pad "22" smd rect
			(at -2.050034 -45.47489 270)
			(size 0.519938 1.4986)
			(layers "F.Cu" "F.Mask" "F.Paste")
			(net "M_C_CPU1_SA_DQS_DP<1>")
		)
		(pad "23" smd rect
			(at -2.050034 -44.625006 270)
			(size 0.519938 1.4986)
			(layers "F.Cu" "F.Mask" "F.Paste")
			(net "M_C_CPU1_SA_DQS_DN<1>")
		)
		(pad "24" smd rect
			(at -2.050034 -43.775122 270)
			(size 0.519938 1.4986)
			(layers "F.Cu" "F.Mask" "F.Paste")
			(net "GND")
		)
		(pad "25" smd rect
			(at -2.050034 -42.924984 270)
			(size 0.519938 1.4986)
			(layers "F.Cu" "F.Mask" "F.Paste")
			(net "M_C_CPU1_SA_DQ<12>")
		)
		(pad "26" smd rect
			(at -2.050034 -42.0751 270)
			(size 0.519938 1.4986)
			(layers "F.Cu" "F.Mask" "F.Paste")
			(net "GND")
		)
		(pad "27" smd rect
			(at -2.050034 -41.224962 270)
			(size 0.519938 1.4986)
			(layers "F.Cu" "F.Mask" "F.Paste")
			(net "M_C_CPU1_SA_DQ<13>")
		)
		(pad "28" smd rect
			(at -2.050034 -40.375078 270)
			(size 0.519938 1.4986)
			(layers "F.Cu" "F.Mask" "F.Paste")
			(net "GND")
		)
		(pad "29" smd rect
			(at -2.050034 -39.52494 270)
			(size 0.519938 1.4986)
			(layers "F.Cu" "F.Mask" "F.Paste")
			(net "M_C_CPU1_SA_DQ<16>")
		)
		(pad "30" smd rect
			(at -2.050034 -38.675056 270)
			(size 0.519938 1.4986)
			(layers "F.Cu" "F.Mask" "F.Paste")
			(net "GND")
		)
		(pad "31" smd rect
			(at -2.050034 -37.824918 270)
			(size 0.519938 1.4986)
			(layers "F.Cu" "F.Mask" "F.Paste")
			(net "M_C_CPU1_SA_DQ<17>")
		)
		(pad "32" smd rect
			(at -2.050034 -36.975034 270)
			(size 0.519938 1.4986)
			(layers "F.Cu" "F.Mask" "F.Paste")
			(net "GND")
		)
		(pad "33" smd rect
			(at -2.050034 -36.124896 270)
			(size 0.519938 1.4986)
			(layers "F.Cu" "F.Mask" "F.Paste")
			(net "M_C_CPU1_SA_DQS_DP<2>")
		)
		(pad "34" smd rect
			(at -2.050034 -35.275012 270)
			(size 0.519938 1.4986)
			(layers "F.Cu" "F.Mask" "F.Paste")
			(net "M_C_CPU1_SA_DQS_DN<2>")
		)
		(pad "35" smd rect
			(at -2.050034 -34.425128 270)
			(size 0.519938 1.4986)
			(layers "F.Cu" "F.Mask" "F.Paste")
			(net "GND")
		)
		(pad "36" smd rect
			(at -2.050034 -33.57499 270)
			(size 0.519938 1.4986)
			(layers "F.Cu" "F.Mask" "F.Paste")
			(net "M_C_CPU1_SA_DQ<20>")
		)
		(pad "37" smd rect
			(at -2.050034 -32.725106 270)
			(size 0.519938 1.4986)
			(layers "F.Cu" "F.Mask" "F.Paste")
			(net "GND")
		)
		(pad "38" smd rect
			(at -2.050034 -31.874968 270)
			(size 0.519938 1.4986)
			(layers "F.Cu" "F.Mask" "F.Paste")
			(net "M_C_CPU1_SA_DQ<21>")
		)
		(pad "39" smd rect
			(at -2.050034 -31.025084 270)
			(size 0.519938 1.4986)
			(layers "F.Cu" "F.Mask" "F.Paste")
			(net "GND")
		)
		(pad "40" smd rect
			(at -2.050034 -30.174946 270)
			(size 0.519938 1.4986)
			(layers "F.Cu" "F.Mask" "F.Paste")
			(net "M_C_CPU1_SA_DQ<24>")
		)
		(pad "41" smd rect
			(at -2.050034 -29.325062 270)
			(size 0.519938 1.4986)
			(layers "F.Cu" "F.Mask" "F.Paste")
			(net "GND")
		)
		(pad "42" smd rect
			(at -2.050034 -28.474924 270)
			(size 0.519938 1.4986)
			(layers "F.Cu" "F.Mask" "F.Paste")
			(net "M_C_CPU1_SA_DQ<25>")
		)
		(pad "43" smd rect
			(at -2.050034 -27.62504 270)
			(size 0.519938 1.4986)
			(layers "F.Cu" "F.Mask" "F.Paste")
			(net "GND")
		)
		(pad "44" smd rect
			(at -2.050034 -26.774902 270)
			(size 0.519938 1.4986)
			(layers "F.Cu" "F.Mask" "F.Paste")
			(net "M_C_CPU1_SA_DQS_DP<3>")
		)
		(pad "45" smd rect
			(at -2.050034 -25.925018 270)
			(size 0.519938 1.4986)
			(layers "F.Cu" "F.Mask" "F.Paste")
			(net "M_C_CPU1_SA_DQS_DN<3>")
		)
	)
)
